(kicad_pcb
	(version 20260206)
	(generator "pcbnew")
	(generator_version "10.0")
	(general
		(thickness 1.6)
		(legacy_teardrops no)
	)
	(paper "A4")
	(title_block
		(title "Wiwynn_Tioga_Pass_MB.brd")
		(comment 1 "Tioga Pass / footprint 949 of 4770 (J8G1), pads 114-204 of 204")
	)
	(layers
		(0 "F.Cu" signal "TOP")
		(4 "In1.Cu" signal "L2GND")
		(6 "In2.Cu" signal "L3")
		(8 "In3.Cu" signal "L4GND")
		(10 "In4.Cu" signal "L5")
		(12 "In5.Cu" signal "L6GND")
		(14 "In6.Cu" signal "L7VCC")
		(16 "In7.Cu" signal "L8VCC")
		(18 "In8.Cu" signal "L9GND")
		(20 "In9.Cu" signal "L10")
		(22 "In10.Cu" signal "L11GND")
		(24 "In11.Cu" signal "L12")
		(26 "In12.Cu" signal "L13GND")
		(2 "B.Cu" signal "BOTTOM")
		(9 "F.Adhes" user "F.Adhesive")
		(11 "B.Adhes" user "B.Adhesive")
		(13 "F.Paste" user "Package Geometry/Pastemask Top")
		(15 "B.Paste" user "Package Geometry/Pastemask Bottom")
		(5 "F.SilkS" user "Ref Des/Silkscreen Top")
		(7 "B.SilkS" user "Ref Des/Silkscreen Bottom")
		(1 "F.Mask" user "Board Geometry/Soldermask Top")
		(3 "B.Mask" user "Board Geometry/Soldermask Bottom")
		(17 "Dwgs.User" user "User.Drawings")
		(19 "Cmts.User" user "User.Comments")
		(21 "Eco1.User" user "User.Eco1")
		(23 "Eco2.User" user "User.Eco2")
		(25 "Edge.Cuts" user "Board Geometry/Outline")
		(27 "Margin" user)
		(31 "F.CrtYd" user "Package Geometry/Place Bound Top")
		(29 "B.CrtYd" user "Package Geometry/Place Bound Bottom")
		(35 "F.Fab" user "Ref Des/Assembly Top")
		(33 "B.Fab" user "Ref Des/Assembly Bottom")
	)
	(footprint ""
		(layer "F.Cu")
		(at 474.080078 -7.789672 -90)
		(property "Reference" "J8G1"
			(at -3.126486 25.39111 0)
			(unlocked yes)
			(layer "F.SilkS")
			(effects
				(font
					(size 0.7874 0.5842)
					(thickness 0.1524)
				)
				(justify left)
			)
		)
		(property "Value" ""
			(at 0 0 270)
			(layer "F.Fab")
			(effects
				(font
					(size 1.27 1.27)
				)
			)
		)
		(duplicate_pad_numbers_are_jumpers no)
		(pad "112" smd rect
			(at 3.4036 47.205392 270)
			(size 1.1938 0.508)
			(layers "F.Cu" "F.Mask" "F.Paste")
			(net "P3E_CPU0_PE1_SS_R_RXN<6>")
		)
		(pad "113" smd rect
			(at 0 48.005492 270)
			(size 1.1938 0.508)
			(layers "F.Cu" "F.Mask" "F.Paste")
			(net "GND")
		)
		(pad "114" smd rect
			(at 3.4036 48.005492 270)
			(size 1.1938 0.508)
			(layers "F.Cu" "F.Mask" "F.Paste")
			(net "P3E_CPU0_PE1_SS_R_RXP<6>")
		)
		(pad "115" smd rect
			(at 0 48.805592 270)
			(size 1.1938 0.508)
			(layers "F.Cu" "F.Mask" "F.Paste")
			(net "P3E_CPU0_PE1_SS_C_TXN<5>")
		)
		(pad "116" smd rect
			(at 3.4036 48.805592 270)
			(size 1.1938 0.508)
			(layers "F.Cu" "F.Mask" "F.Paste")
			(net "GND")
		)
		(pad "117" smd rect
			(at 0 49.605692 270)
			(size 1.1938 0.508)
			(layers "F.Cu" "F.Mask" "F.Paste")
			(net "P3E_CPU0_PE1_SS_C_TXP<5>")
		)
		(pad "118" smd rect
			(at 3.4036 49.605692 270)
			(size 1.1938 0.508)
			(layers "F.Cu" "F.Mask" "F.Paste")
			(net "P3E_CPU0_PE1_SS_R_RXN<5>")
		)
		(pad "119" smd rect
			(at 0 50.405792 270)
			(size 1.1938 0.508)
			(layers "F.Cu" "F.Mask" "F.Paste")
			(net "GND")
		)
		(pad "120" smd rect
			(at 3.4036 50.405792 270)
			(size 1.1938 0.508)
			(layers "F.Cu" "F.Mask" "F.Paste")
			(net "P3E_CPU0_PE1_SS_R_RXP<5>")
		)
		(pad "121" smd rect
			(at 0 51.205892 270)
			(size 1.1938 0.508)
			(layers "F.Cu" "F.Mask" "F.Paste")
			(net "P3E_CPU0_PE1_SS_C_TXN<4>")
		)
		(pad "122" smd rect
			(at 3.4036 51.205892 270)
			(size 1.1938 0.508)
			(layers "F.Cu" "F.Mask" "F.Paste")
			(net "GND")
		)
		(pad "123" smd rect
			(at 0 52.005992 270)
			(size 1.1938 0.508)
			(layers "F.Cu" "F.Mask" "F.Paste")
			(net "P3E_CPU0_PE1_SS_C_TXP<4>")
		)
		(pad "124" smd rect
			(at 3.4036 52.005992 270)
			(size 1.1938 0.508)
			(layers "F.Cu" "F.Mask" "F.Paste")
			(net "P3E_CPU0_PE1_SS_R_RXN<4>")
		)
		(pad "125" smd rect
			(at 0 52.806092 270)
			(size 1.1938 0.508)
			(layers "F.Cu" "F.Mask" "F.Paste")
			(net "GND")
		)
		(pad "126" smd rect
			(at 3.4036 52.806092 270)
			(size 1.1938 0.508)
			(layers "F.Cu" "F.Mask" "F.Paste")
			(net "P3E_CPU0_PE1_SS_R_RXP<4>")
		)
		(pad "127" smd rect
			(at 0 53.606192 270)
			(size 1.1938 0.508)
			(layers "F.Cu" "F.Mask" "F.Paste")
			(net "P3E_CPU0_PE1_SS_C_TXN<3>")
		)
		(pad "128" smd rect
			(at 3.4036 53.606192 270)
			(size 1.1938 0.508)
			(layers "F.Cu" "F.Mask" "F.Paste")
			(net "GND")
		)
		(pad "129" smd rect
			(at 0 54.406292 270)
			(size 1.1938 0.508)
			(layers "F.Cu" "F.Mask" "F.Paste")
			(net "P3E_CPU0_PE1_SS_C_TXP<3>")
		)
		(pad "130" smd rect
			(at 3.4036 54.406292 270)
			(size 1.1938 0.508)
			(layers "F.Cu" "F.Mask" "F.Paste")
			(net "P3E_CPU0_PE1_SS_R_RXN<3>")
		)
		(pad "131" smd rect
			(at 0 55.206392 270)
			(size 1.1938 0.508)
			(layers "F.Cu" "F.Mask" "F.Paste")
			(net "GND")
		)
		(pad "132" smd rect
			(at 3.4036 55.206392 270)
			(size 1.1938 0.508)
			(layers "F.Cu" "F.Mask" "F.Paste")
			(net "P3E_CPU0_PE1_SS_R_RXP<3>")
		)
		(pad "133" smd rect
			(at 0 56.006492 270)
			(size 1.1938 0.508)
			(layers "F.Cu" "F.Mask" "F.Paste")
			(net "P3E_CPU0_PE1_SS_C_TXN<2>")
		)
		(pad "134" smd rect
			(at 3.4036 56.006492 270)
			(size 1.1938 0.508)
			(layers "F.Cu" "F.Mask" "F.Paste")
			(net "GND")
		)
		(pad "135" smd rect
			(at 0 56.806592 270)
			(size 1.1938 0.508)
			(layers "F.Cu" "F.Mask" "F.Paste")
			(net "P3E_CPU0_PE1_SS_C_TXP<2>")
		)
		(pad "136" smd rect
			(at 3.4036 56.806592 270)
			(size 1.1938 0.508)
			(layers "F.Cu" "F.Mask" "F.Paste")
			(net "P3E_CPU0_PE1_SS_R_RXN<2>")
		)
		(pad "137" smd rect
			(at 0 57.606692 270)
			(size 1.1938 0.508)
			(layers "F.Cu" "F.Mask" "F.Paste")
			(net "GND")
		)
		(pad "138" smd rect
			(at 3.4036 57.606692 270)
			(size 1.1938 0.508)
			(layers "F.Cu" "F.Mask" "F.Paste")
			(net "P3E_CPU0_PE1_SS_R_RXP<2>")
		)
		(pad "139" smd rect
			(at 0 58.406792 270)
			(size 1.1938 0.508)
			(layers "F.Cu" "F.Mask" "F.Paste")
			(net "P3E_CPU0_PE1_SS_C_TXN<1>")
		)
		(pad "140" smd rect
			(at 3.4036 58.406792 270)
			(size 1.1938 0.508)
			(layers "F.Cu" "F.Mask" "F.Paste")
			(net "GND")
		)
		(pad "141" smd rect
			(at 0 59.206892 270)
			(size 1.1938 0.508)
			(layers "F.Cu" "F.Mask" "F.Paste")
			(net "P3E_CPU0_PE1_SS_C_TXP<1>")
		)
		(pad "142" smd rect
			(at 3.4036 59.206892 270)
			(size 1.1938 0.508)
			(layers "F.Cu" "F.Mask" "F.Paste")
			(net "P3E_CPU0_PE1_SS_R_RXN<1>")
		)
		(pad "143" smd rect
			(at 0 60.006992 270)
			(size 1.1938 0.508)
			(layers "F.Cu" "F.Mask" "F.Paste")
			(net "GND")
		)
		(pad "144" smd rect
			(at 3.4036 60.006992 270)
			(size 1.1938 0.508)
			(layers "F.Cu" "F.Mask" "F.Paste")
			(net "P3E_CPU0_PE1_SS_R_RXP<1>")
		)
		(pad "145" smd rect
			(at 0 60.807092 270)
			(size 1.1938 0.508)
			(layers "F.Cu" "F.Mask" "F.Paste")
			(net "P3E_CPU0_PE1_SS_C_TXN<0>")
		)
		(pad "146" smd rect
			(at 3.4036 60.807092 270)
			(size 1.1938 0.508)
			(layers "F.Cu" "F.Mask" "F.Paste")
			(net "GND")
		)
		(pad "147" smd rect
			(at 0 61.607192 270)
			(size 1.1938 0.508)
			(layers "F.Cu" "F.Mask" "F.Paste")
			(net "P3E_CPU0_PE1_SS_C_TXP<0>")
		)
		(pad "148" smd rect
			(at 3.4036 61.607192 270)
			(size 1.1938 0.508)
			(layers "F.Cu" "F.Mask" "F.Paste")
			(net "P3E_CPU0_PE1_SS_R_RXN<0>")
		)
		(pad "149" smd rect
			(at 0 62.407292 270)
			(size 1.1938 0.508)
			(layers "F.Cu" "F.Mask" "F.Paste")
			(net "GND")
		)
		(pad "150" smd rect
			(at 3.4036 62.407292 270)
			(size 1.1938 0.508)
			(layers "F.Cu" "F.Mask" "F.Paste")
			(net "P3E_CPU0_PE1_SS_R_RXP<0>")
		)
		(pad "151" smd rect
			(at 0 63.207392 270)
			(size 1.1938 0.508)
			(layers "F.Cu" "F.Mask" "F.Paste")
			(net "P3E_CPU0_PE2_SS_C_TXN<0>")
		)
		(pad "152" smd rect
			(at 3.4036 63.207392 270)
			(size 1.1938 0.508)
			(layers "F.Cu" "F.Mask" "F.Paste")
			(net "GND")
		)
		(pad "153" smd rect
			(at 0 64.007492 270)
			(size 1.1938 0.508)
			(layers "F.Cu" "F.Mask" "F.Paste")
			(net "P3E_CPU0_PE2_SS_C_TXP<0>")
		)
		(pad "154" smd rect
			(at 3.4036 64.007492 270)
			(size 1.1938 0.508)
			(layers "F.Cu" "F.Mask" "F.Paste")
			(net "P3E_CPU0_PE2_SS_RXN<0>")
		)
		(pad "155" smd rect
			(at 0 64.807592 270)
			(size 1.1938 0.508)
			(layers "F.Cu" "F.Mask" "F.Paste")
			(net "GND")
		)
		(pad "156" smd rect
			(at 3.4036 64.807592 270)
			(size 1.1938 0.508)
			(layers "F.Cu" "F.Mask" "F.Paste")
			(net "P3E_CPU0_PE2_SS_RXP<0>")
		)
		(pad "157" smd rect
			(at 0 65.607692 270)
			(size 1.1938 0.508)
			(layers "F.Cu" "F.Mask" "F.Paste")
			(net "P3E_CPU0_PE2_SS_C_TXP<1>")
		)
		(pad "158" smd rect
			(at 3.4036 65.607692 270)
			(size 1.1938 0.508)
			(layers "F.Cu" "F.Mask" "F.Paste")
			(net "GND")
		)
		(pad "159" smd rect
			(at 0 66.407792 270)
			(size 1.1938 0.508)
			(layers "F.Cu" "F.Mask" "F.Paste")
			(net "P3E_CPU0_PE2_SS_C_TXN<1>")
		)
		(pad "160" smd rect
			(at 3.4036 66.407792 270)
			(size 1.1938 0.508)
			(layers "F.Cu" "F.Mask" "F.Paste")
			(net "P3E_CPU0_PE2_SS_RXN<1>")
		)
		(pad "161" smd rect
			(at 0 67.207892 270)
			(size 1.1938 0.508)
			(layers "F.Cu" "F.Mask" "F.Paste")
			(net "GND")
		)
		(pad "162" smd rect
			(at 3.4036 67.207892 270)
			(size 1.1938 0.508)
			(layers "F.Cu" "F.Mask" "F.Paste")
			(net "P3E_CPU0_PE2_SS_RXP<1>")
		)
		(pad "163" smd rect
			(at 0 68.007992 270)
			(size 1.1938 0.508)
			(layers "F.Cu" "F.Mask" "F.Paste")
			(net "P3E_CPU0_PE2_SS_C_TXN<2>")
		)
		(pad "164" smd rect
			(at 3.4036 68.007992 270)
			(size 1.1938 0.508)
			(layers "F.Cu" "F.Mask" "F.Paste")
			(net "GND")
		)
		(pad "165" smd rect
			(at 0 68.808092 270)
			(size 1.1938 0.508)
			(layers "F.Cu" "F.Mask" "F.Paste")
			(net "P3E_CPU0_PE2_SS_C_TXP<2>")
		)
		(pad "166" smd rect
			(at 3.4036 68.808092 270)
			(size 1.1938 0.508)
			(layers "F.Cu" "F.Mask" "F.Paste")
			(net "P3E_CPU0_PE2_SS_RXN<2>")
		)
		(pad "167" smd rect
			(at 0 69.608192 270)
			(size 1.1938 0.508)
			(layers "F.Cu" "F.Mask" "F.Paste")
			(net "GND")
		)
		(pad "168" smd rect
			(at 3.4036 69.608192 270)
			(size 1.1938 0.508)
			(layers "F.Cu" "F.Mask" "F.Paste")
			(net "P3E_CPU0_PE2_SS_RXP<2>")
		)
		(pad "169" smd rect
			(at 0 70.408292 270)
			(size 1.1938 0.508)
			(layers "F.Cu" "F.Mask" "F.Paste")
			(net "P3E_CPU0_PE2_SS_C_TXN<3>")
		)
		(pad "170" smd rect
			(at 3.4036 70.408292 270)
			(size 1.1938 0.508)
			(layers "F.Cu" "F.Mask" "F.Paste")
			(net "GND")
		)
		(pad "171" smd rect
			(at 0 71.208392 270)
			(size 1.1938 0.508)
			(layers "F.Cu" "F.Mask" "F.Paste")
			(net "P3E_CPU0_PE2_SS_C_TXP<3>")
		)
		(pad "172" smd rect
			(at 3.4036 71.208392 270)
			(size 1.1938 0.508)
			(layers "F.Cu" "F.Mask" "F.Paste")
			(net "P3E_CPU0_PE2_SS_RXN<3>")
		)
		(pad "173" smd rect
			(at 0 72.008492 270)
			(size 1.1938 0.508)
			(layers "F.Cu" "F.Mask" "F.Paste")
			(net "GND")
		)
		(pad "174" smd rect
			(at 3.4036 72.008492 270)
			(size 1.1938 0.508)
			(layers "F.Cu" "F.Mask" "F.Paste")
			(net "P3E_CPU0_PE2_SS_RXP<3>")
		)
		(pad "175" smd rect
			(at 0 72.808592 270)
			(size 1.1938 0.508)
			(layers "F.Cu" "F.Mask" "F.Paste")
			(net "P3E_CPU0_PE2_SS_C_TXN<4>")
		)
		(pad "176" smd rect
			(at 3.4036 72.808592 270)
			(size 1.1938 0.508)
			(layers "F.Cu" "F.Mask" "F.Paste")
			(net "GND")
		)
		(pad "177" smd rect
			(at 0 73.608692 270)
			(size 1.1938 0.508)
			(layers "F.Cu" "F.Mask" "F.Paste")
			(net "P3E_CPU0_PE2_SS_C_TXP<4>")
		)
		(pad "178" smd rect
			(at 3.4036 73.608692 270)
			(size 1.1938 0.508)
			(layers "F.Cu" "F.Mask" "F.Paste")
			(net "P3E_CPU0_PE2_SS_RXN<4>")
		)
		(pad "179" smd rect
			(at 0 74.408792 270)
			(size 1.1938 0.508)
			(layers "F.Cu" "F.Mask" "F.Paste")
			(net "GND")
		)
		(pad "180" smd rect
			(at 3.4036 74.408792 270)
			(size 1.1938 0.508)
			(layers "F.Cu" "F.Mask" "F.Paste")
			(net "P3E_CPU0_PE2_SS_RXP<4>")
		)
		(pad "181" smd rect
			(at 0 75.208892 270)
			(size 1.1938 0.508)
			(layers "F.Cu" "F.Mask" "F.Paste")
			(net "P3E_CPU0_PE2_SS_C_TXN<5>")
		)
		(pad "182" smd rect
			(at 3.4036 75.208892 270)
			(size 1.1938 0.508)
			(layers "F.Cu" "F.Mask" "F.Paste")
			(net "GND")
		)
		(pad "183" smd rect
			(at 0 76.008992 270)
			(size 1.1938 0.508)
			(layers "F.Cu" "F.Mask" "F.Paste")
			(net "P3E_CPU0_PE2_SS_C_TXP<5>")
		)
		(pad "184" smd rect
			(at 3.4036 76.008992 270)
			(size 1.1938 0.508)
			(layers "F.Cu" "F.Mask" "F.Paste")
			(net "P3E_CPU0_PE2_SS_RXN<5>")
		)
		(pad "185" smd rect
			(at 0 76.809092 270)
			(size 1.1938 0.508)
			(layers "F.Cu" "F.Mask" "F.Paste")
			(net "GND")
		)
		(pad "186" smd rect
			(at 3.4036 76.809092 270)
			(size 1.1938 0.508)
			(layers "F.Cu" "F.Mask" "F.Paste")
			(net "P3E_CPU0_PE2_SS_RXP<5>")
		)
		(pad "187" smd rect
			(at 0 77.609192 270)
			(size 1.1938 0.508)
			(layers "F.Cu" "F.Mask" "F.Paste")
			(net "P3E_CPU0_PE2_SS_C_TXN<6>")
		)
		(pad "188" smd rect
			(at 3.4036 77.609192 270)
			(size 1.1938 0.508)
			(layers "F.Cu" "F.Mask" "F.Paste")
			(net "GND")
		)
		(pad "189" smd rect
			(at 0 78.409292 270)
			(size 1.1938 0.508)
			(layers "F.Cu" "F.Mask" "F.Paste")
			(net "P3E_CPU0_PE2_SS_C_TXP<6>")
		)
		(pad "190" smd rect
			(at 3.4036 78.409292 270)
			(size 1.1938 0.508)
			(layers "F.Cu" "F.Mask" "F.Paste")
			(net "P3E_CPU0_PE2_SS_RXP<6>")
		)
		(pad "191" smd rect
			(at 0 79.209392 270)
			(size 1.1938 0.508)
			(layers "F.Cu" "F.Mask" "F.Paste")
			(net "GND")
		)
		(pad "192" smd rect
			(at 3.4036 79.209392 270)
			(size 1.1938 0.508)
			(layers "F.Cu" "F.Mask" "F.Paste")
			(net "P3E_CPU0_PE2_SS_RXN<6>")
		)
		(pad "193" smd rect
			(at 0 80.009492 270)
			(size 1.1938 0.508)
			(layers "F.Cu" "F.Mask" "F.Paste")
			(net "P3E_CPU0_PE2_SS_C_TXN<7>")
		)
		(pad "194" smd rect
			(at 3.4036 80.009492 270)
			(size 1.1938 0.508)
			(layers "F.Cu" "F.Mask" "F.Paste")
			(net "GND")
		)
		(pad "195" smd rect
			(at 0 80.809592 270)
			(size 1.1938 0.508)
			(layers "F.Cu" "F.Mask" "F.Paste")
			(net "P3E_CPU0_PE2_SS_C_TXP<7>")
		)
		(pad "196" smd rect
			(at 3.4036 80.809592 270)
			(size 1.1938 0.508)
			(layers "F.Cu" "F.Mask" "F.Paste")
			(net "P3E_CPU0_PE2_SS_RXN<7>")
		)
		(pad "197" smd rect
			(at 0 81.609692 270)
			(size 1.1938 0.508)
			(layers "F.Cu" "F.Mask" "F.Paste")
			(net "GND")
		)
		(pad "198" smd rect
			(at 3.4036 81.609692 270)
			(size 1.1938 0.508)
			(layers "F.Cu" "F.Mask" "F.Paste")
			(net "P3E_CPU0_PE2_SS_RXP<7>")
		)
		(pad "199" smd rect
			(at 0 82.409792 270)
			(size 1.1938 0.508)
			(layers "F.Cu" "F.Mask" "F.Paste")
			(net "FM_PRSNT_2_6_N")
		)
		(pad "200" smd rect
			(at 3.4036 82.409792 270)
			(size 1.1938 0.508)
			(layers "F.Cu" "F.Mask" "F.Paste")
			(net "GND")
		)
		(pad "MH1" thru_hole circle
			(at 1.7018 -3.845052 270)
			(size 1.4224 1.4224)
			(drill 1.0414)
			(layers "*.Cu" "*.Mask")
			(remove_unused_layers no)
			(net "GND")
			(clearance 0.127)
			(thermal_gap 0.127)
		)
		(pad "MH2" thru_hole circle
			(at 1.7018 86.254844 270)
			(size 1.4224 1.4224)
			(drill 1.0414)
			(layers "*.Cu" "*.Mask")
			(remove_unused_layers no)
			(net "GND")
			(clearance 0.127)
			(thermal_gap 0.127)
		)
	)
)
